(kicad_pcb
	(version 20260206)
	(generator "pcbnew")
	(generator_version "10.0")
	(general
		(thickness 1.6)
		(legacy_teardrops no)
	)
	(paper "A4")
	(title_block
		(title "Wiwynn_Tioga_Pass_MB.brd")
		(comment 1 "Tioga Pass / footprints 3623-3630 of 4770")
	)
	(layers
		(0 "F.Cu" signal "TOP")
		(4 "In1.Cu" signal "L2GND")
		(6 "In2.Cu" signal "L3")
		(8 "In3.Cu" signal "L4GND")
		(10 "In4.Cu" signal "L5")
		(12 "In5.Cu" signal "L6GND")
		(14 "In6.Cu" signal "L7VCC")
		(16 "In7.Cu" signal "L8VCC")
		(18 "In8.Cu" signal "L9GND")
		(20 "In9.Cu" signal "L10")
		(22 "In10.Cu" signal "L11GND")
		(24 "In11.Cu" signal "L12")
		(26 "In12.Cu" signal "L13GND")
		(2 "B.Cu" signal "BOTTOM")
		(9 "F.Adhes" user "F.Adhesive")
		(11 "B.Adhes" user "B.Adhesive")
		(13 "F.Paste" user "Package Geometry/Pastemask Top")
		(15 "B.Paste" user "Package Geometry/Pastemask Bottom")
		(5 "F.SilkS" user "Ref Des/Silkscreen Top")
		(7 "B.SilkS" user "Ref Des/Silkscreen Bottom")
		(1 "F.Mask" user "Board Geometry/Soldermask Top")
		(3 "B.Mask" user "Board Geometry/Soldermask Bottom")
		(17 "Dwgs.User" user "User.Drawings")
		(19 "Cmts.User" user "User.Comments")
		(21 "Eco1.User" user "User.Eco1")
		(23 "Eco2.User" user "User.Eco2")
		(25 "Edge.Cuts" user "Board Geometry/Outline")
		(27 "Margin" user)
		(31 "F.CrtYd" user "Package Geometry/Place Bound Top")
		(29 "B.CrtYd" user "Package Geometry/Place Bound Bottom")
		(35 "F.Fab" user "Ref Des/Assembly Top")
		(33 "B.Fab" user "Ref Des/Assembly Bottom")
	)
	(footprint ""
		(layer "B.Cu")
		(at 24.638 -56.8452 -90)
		(property "Reference" "R9R4"
			(at 0 0 90)
			(layer "B.SilkS")
			(hide yes)
			(effects
				(font
					(size 1.27 1.27)
				)
				(justify mirror)
			)
		)
		(property "Value" ""
			(at 0 0 90)
			(layer "B.Fab")
			(effects
				(font
					(size 1.27 1.27)
				)
				(justify mirror)
			)
		)
		(duplicate_pad_numbers_are_jumpers no)
		(fp_rect
			(start 0.2794 0.9906)
			(end -0.2794 -0.1016)
			(stroke
				(width 0)
				(type default)
			)
			(fill no)
			(layer "B.CrtYd")
		)
		(fp_line
			(start -0.2794 0.9906)
			(end -0.2794 -0.1016)
			(stroke
				(width 0.1)
				(type default)
			)
			(layer "B.Fab")
		)
		(fp_line
			(start 0.2794 0.9906)
			(end -0.2794 0.9906)
			(stroke
				(width 0.1)
				(type default)
			)
			(layer "B.Fab")
		)
		(fp_line
			(start -0.2794 -0.1016)
			(end 0.2794 -0.1016)
			(stroke
				(width 0.1)
				(type default)
			)
			(layer "B.Fab")
		)
		(fp_line
			(start 0.2794 -0.1016)
			(end 0.2794 0.9906)
			(stroke
				(width 0.1)
				(type default)
			)
			(layer "B.Fab")
		)
		(pad "1" smd rect
			(at 0 0 90)
			(size 0.508 0.508)
			(layers "B.Cu" "B.Mask" "B.Paste")
			(net "A_HSC_GATE")
		)
		(pad "2" smd rect
			(at 0 0.889 90)
			(size 0.508 0.508)
			(layers "B.Cu" "B.Mask" "B.Paste")
			(net "A_HSC_GATE2_R")
		)
		(zone
			(layer "B.Cu")
			(hatch none 0.5)
			(connect_pads
				(clearance 0)
			)
			(min_thickness 0.25)
			(keepout
				(tracks not_allowed)
				(vias allowed)
				(pads allowed)
				(copperpour not_allowed)
				(footprints allowed)
			)
			(placement
				(enabled no)
				(sheetname "")
			)
			(fill
				(thermal_gap 0.5)
				(thermal_bridge_width 0.5)
				(island_removal_mode 0)
			)
			(polygon
				(pts
					(xy 24.003 -56.5912) (xy 24.384 -56.5912) (xy 24.384 -57.0992) (xy 24.003 -57.0992)
				)
			)
		)
		(zone
			(layer "B.Cu")
			(hatch none 0.5)
			(connect_pads
				(clearance 0)
			)
			(min_thickness 0.25)
			(keepout
				(tracks allowed)
				(vias not_allowed)
				(pads allowed)
				(copperpour not_allowed)
				(footprints allowed)
			)
			(placement
				(enabled no)
				(sheetname "")
			)
			(fill
				(thermal_gap 0.5)
				(thermal_bridge_width 0.5)
				(island_removal_mode 0)
			)
			(polygon
				(pts
					(xy 24.003 -56.5912) (xy 24.384 -56.5912) (xy 24.384 -57.0992) (xy 24.003 -57.0992)
				)
			)
		)
	)
	(footprint ""
		(layer "B.Cu")
		(at 355.514148 -137.904728 -90)
		(property "Reference" "R12W7"
			(at 0 0 90)
			(layer "B.SilkS")
			(hide yes)
			(effects
				(font
					(size 1.27 1.27)
				)
				(justify mirror)
			)
		)
		(property "Value" "*"
			(at 0 -8.9535 270)
			(unlocked yes)
			(layer "B.Fab")
			(hide yes)
			(effects
				(font
					(size 1.27 1.016)
					(thickness 0.1524)
				)
				(justify mirror)
			)
		)
		(property "Device Type" "665KR5B-1-GP_SMD-RG3-665KR5B-1A"
			(at 0 -10.6299 270)
			(unlocked yes)
			(layer "B.Fab")
			(hide yes)
			(effects
				(font
					(size 1.27 1.016)
					(thickness 0.1524)
				)
				(justify mirror)
			)
		)
		(duplicate_pad_numbers_are_jumpers no)
		(fp_line
			(start -0.889 1.7018)
			(end -0.889 -0.508)
			(stroke
				(width 0.1524)
				(type default)
			)
			(layer "B.SilkS")
		)
		(fp_line
			(start 0.889 1.7018)
			(end -0.889 1.7018)
			(stroke
				(width 0.1524)
				(type default)
			)
			(layer "B.SilkS")
		)
		(fp_line
			(start 0.889 0.0762)
			(end 0.889 1.7018)
			(stroke
				(width 0.1524)
				(type default)
			)
			(layer "B.SilkS")
		)
		(fp_line
			(start -0.889 -1.7018)
			(end -0.889 -0.381)
			(stroke
				(width 0.1524)
				(type default)
			)
			(layer "B.SilkS")
		)
		(fp_line
			(start -0.889 -1.7018)
			(end 0.889 -1.7018)
			(stroke
				(width 0.1524)
				(type default)
			)
			(layer "B.SilkS")
		)
		(fp_line
			(start 0.889 -1.7018)
			(end 0.889 0.2794)
			(stroke
				(width 0.1524)
				(type default)
			)
			(layer "B.SilkS")
		)
		(fp_poly
			(pts
				(xy -0.9652 -1.778) (xy -0.9652 1.778) (xy 0.9652 1.778) (xy 0.9652 -1.778)
			)
			(stroke
				(width 0)
				(type default)
			)
			(fill no)
			(layer "B.CrtYd")
		)
		(fp_rect
			(start 0.9652 1.778)
			(end -0.9652 -1.778)
			(stroke
				(width 0)
				(type default)
			)
			(fill no)
			(layer "B.Fab")
		)
		(pad "1" smd rect
			(at 0 -0.9652 90)
			(size 1.397 1.143)
			(layers "B.Cu" "B.Mask" "B.Paste")
			(net "P12V_NVDIMM_DEF_D")
		)
		(pad "2" smd rect
			(at 0 0.9652 90)
			(size 1.397 1.143)
			(layers "B.Cu" "B.Mask" "B.Paste")
			(net "VR_PVDDQ_DEF_VINSEN")
		)
	)
	(footprint ""
		(layer "B.Cu")
		(at 99.034854 -77.82814)
		(property "Reference" "C8P18"
			(at 0 0 0)
			(layer "B.SilkS")
			(hide yes)
			(effects
				(font
					(size 1.27 1.27)
				)
				(justify mirror)
			)
		)
		(property "Value" ""
			(at 0 0 0)
			(layer "B.Fab")
			(effects
				(font
					(size 1.27 1.27)
				)
				(justify mirror)
			)
		)
		(duplicate_pad_numbers_are_jumpers no)
		(fp_poly
			(pts
				(xy 0.7239 -0.2159) (xy -0.7239 -0.2159) (xy -0.7239 1.9939) (xy 0.7239 1.9939)
			)
			(stroke
				(width 0)
				(type default)
			)
			(fill no)
			(layer "B.CrtYd")
		)
		(fp_line
			(start -0.7239 -0.2159)
			(end 0.7239 -0.2159)
			(stroke
				(width 0.1)
				(type default)
			)
			(layer "B.Fab")
		)
		(fp_line
			(start -0.7239 1.9939)
			(end -0.7239 -0.2159)
			(stroke
				(width 0.1)
				(type default)
			)
			(layer "B.Fab")
		)
		(fp_line
			(start 0.7239 -0.2159)
			(end 0.7239 1.9939)
			(stroke
				(width 0.1)
				(type default)
			)
			(layer "B.Fab")
		)
		(fp_line
			(start 0.7239 1.9939)
			(end -0.7239 1.9939)
			(stroke
				(width 0.1)
				(type default)
			)
			(layer "B.Fab")
		)
		(pad "1" smd rect
			(at 0 0 180)
			(size 1.27 1.016)
			(layers "B.Cu" "B.Mask" "B.Paste")
			(net "PVCCIN_CPU1")
		)
		(pad "2" smd rect
			(at 0 1.778 180)
			(size 1.27 1.016)
			(layers "B.Cu" "B.Mask" "B.Paste")
			(net "GND")
		)
		(zone
			(layer "B.Cu")
			(hatch none 0.5)
			(connect_pads
				(clearance 0)
			)
			(min_thickness 0.25)
			(keepout
				(tracks not_allowed)
				(vias allowed)
				(pads allowed)
				(copperpour not_allowed)
				(footprints allowed)
			)
			(placement
				(enabled no)
				(sheetname "")
			)
			(fill
				(thermal_gap 0.5)
				(thermal_bridge_width 0.5)
				(island_removal_mode 0)
			)
			(polygon
				(pts
					(xy 99.669854 -77.32014) (xy 98.399854 -77.32014) (xy 98.399854 -76.55814) (xy 99.669854 -76.55814)
				)
			)
		)
	)
	(footprint ""
		(layer "B.Cu")
		(at 320.194432 1.7018 90)
		(property "Reference" "C4U3"
			(at 0 0 90)
			(layer "B.SilkS")
			(hide yes)
			(effects
				(font
					(size 1.27 1.27)
				)
				(justify mirror)
			)
		)
		(property "Value" ""
			(at 0 0 90)
			(layer "B.Fab")
			(effects
				(font
					(size 1.27 1.27)
				)
				(justify mirror)
			)
		)
		(duplicate_pad_numbers_are_jumpers no)
		(fp_poly
			(pts
				(xy 0.4953 -0.2032) (xy -0.4953 -0.2032) (xy -0.4953 1.6002) (xy 0.4953 1.6002)
			)
			(stroke
				(width 0)
				(type default)
			)
			(fill no)
			(layer "B.CrtYd")
		)
		(fp_line
			(start 0.4953 -0.2032)
			(end -0.4953 -0.2032)
			(stroke
				(width 0.1)
				(type default)
			)
			(layer "B.Fab")
		)
		(fp_line
			(start -0.4953 -0.2032)
			(end -0.4953 1.6002)
			(stroke
				(width 0.1)
				(type default)
			)
			(layer "B.Fab")
		)
		(fp_line
			(start 0.4953 1.6002)
			(end 0.4953 -0.2032)
			(stroke
				(width 0.1)
				(type default)
			)
			(layer "B.Fab")
		)
		(fp_line
			(start -0.4953 1.6002)
			(end 0.4953 1.6002)
			(stroke
				(width 0.1)
				(type default)
			)
			(layer "B.Fab")
		)
		(pad "1" smd rect
			(at 0 0 270)
			(size 0.762 0.889)
			(layers "B.Cu" "B.Mask" "B.Paste")
			(net "PVPP_ABC")
		)
		(pad "2" smd rect
			(at 0 1.397 270)
			(size 0.762 0.889)
			(layers "B.Cu" "B.Mask" "B.Paste")
			(net "GND")
		)
		(zone
			(layer "B.Cu")
			(hatch none 0.5)
			(connect_pads
				(clearance 0)
			)
			(min_thickness 0.25)
			(keepout
				(tracks not_allowed)
				(vias allowed)
				(pads allowed)
				(copperpour not_allowed)
				(footprints allowed)
			)
			(placement
				(enabled no)
				(sheetname "")
			)
			(fill
				(thermal_gap 0.5)
				(thermal_bridge_width 0.5)
				(island_removal_mode 0)
			)
			(polygon
				(pts
					(xy 320.638932 1.3208) (xy 320.638932 2.0828) (xy 321.146932 2.0828) (xy 321.146932 1.3208)
				)
			)
		)
	)
	(footprint ""
		(layer "B.Cu")
		(at 412.877 -43.053 90)
		(property "Reference" "R25W67"
			(at 0 0 90)
			(layer "B.SilkS")
			(hide yes)
			(effects
				(font
					(size 1.27 1.27)
				)
				(justify mirror)
			)
		)
		(property "Value" "*"
			(at -0.064008 -4.108196 90)
			(unlocked yes)
			(layer "B.Fab")
			(hide yes)
			(effects
				(font
					(size 1.27 1.016)
					(thickness 0.1524)
				)
				(justify mirror)
			)
		)
		(property "Device Type" "200R2F-L1-GP_SMD-RG4-200R2F-L1A"
			(at -0.064008 -5.632196 90)
			(unlocked yes)
			(layer "B.Fab")
			(hide yes)
			(effects
				(font
					(size 1.27 1.016)
					(thickness 0.1524)
				)
				(justify mirror)
			)
		)
		(duplicate_pad_numbers_are_jumpers no)
		(fp_line
			(start 0.508 -0.9398)
			(end 0.508 0.9398)
			(stroke
				(width 0.1524)
				(type default)
			)
			(layer "B.SilkS")
		)
		(fp_line
			(start -0.508 -0.9398)
			(end 0.508 -0.9398)
			(stroke
				(width 0.1524)
				(type default)
			)
			(layer "B.SilkS")
		)
		(fp_rect
			(start 0.508 0.9398)
			(end -0.508 -0.9398)
			(stroke
				(width 0)
				(type default)
			)
			(fill no)
			(layer "B.CrtYd")
		)
		(fp_rect
			(start 0.508 0.9398)
			(end -0.508 -0.9398)
			(stroke
				(width 0)
				(type default)
			)
			(fill no)
			(layer "B.Fab")
		)
		(pad "1" smd custom
			(at 0 -0.4445 270)
			(size 0.1397 0.1397)
			(layers "B.Cu" "B.Mask" "B.Paste")
			(net "PD_PEREXT")
			(options
				(clearance outline)
				(anchor circle)
			)
			(primitives
				(gr_poly
					(pts
						(arc
							(start -0.1778 0.2794)
							(mid -0.249642 0.249642)
							(end -0.2794 0.1778)
						)
						(arc
							(start -0.2794 -0.1778)
							(mid -0.249642 -0.249642)
							(end -0.1778 -0.2794)
						)
						(arc
							(start 0.1778 -0.2794)
							(mid 0.249642 -0.249642)
							(end 0.2794 -0.1778)
						)
						(arc
							(start 0.2794 0.1778)
							(mid 0.249642 0.249642)
							(end 0.1778 0.2794)
						)
					)
					(width 0)
					(fill yes)
				)
			)
		)
		(pad "2" smd custom
			(at 0 0.4445 270)
			(size 0.1397 0.1397)
			(layers "B.Cu" "B.Mask" "B.Paste")
			(net "GND")
			(options
				(clearance outline)
				(anchor circle)
			)
			(primitives
				(gr_poly
					(pts
						(arc
							(start -0.1778 0.2794)
							(mid -0.249642 0.249642)
							(end -0.2794 0.1778)
						)
						(arc
							(start -0.2794 -0.1778)
							(mid -0.249642 -0.249642)
							(end -0.1778 -0.2794)
						)
						(arc
							(start 0.1778 -0.2794)
							(mid 0.249642 -0.249642)
							(end 0.2794 -0.1778)
						)
						(arc
							(start 0.2794 0.1778)
							(mid 0.249642 0.249642)
							(end 0.1778 0.2794)
						)
					)
					(width 0)
					(fill yes)
				)
			)
		)
	)
	(footprint ""
		(layer "B.Cu")
		(at 156.414978 -119.384826 -90)
		(property "Reference" "R7M9"
			(at 0 0 90)
			(layer "B.SilkS")
			(hide yes)
			(effects
				(font
					(size 1.27 1.27)
				)
				(justify mirror)
			)
		)
		(property "Value" ""
			(at 0 0 90)
			(layer "B.Fab")
			(effects
				(font
					(size 1.27 1.27)
				)
				(justify mirror)
			)
		)
		(duplicate_pad_numbers_are_jumpers no)
		(fp_poly
			(pts
				(xy 0.2794 -0.1016) (xy -0.2794 -0.1016) (xy -0.2794 0.9906) (xy 0.2794 0.9906)
			)
			(stroke
				(width 0)
				(type default)
			)
			(fill no)
			(layer "B.CrtYd")
		)
		(fp_line
			(start -0.2794 0.9906)
			(end -0.2794 -0.1016)
			(stroke
				(width 0.1)
				(type default)
			)
			(layer "B.Fab")
		)
		(fp_line
			(start 0.2794 0.9906)
			(end -0.2794 0.9906)
			(stroke
				(width 0.1)
				(type default)
			)
			(layer "B.Fab")
		)
		(fp_line
			(start -0.2794 -0.1016)
			(end 0.2794 -0.1016)
			(stroke
				(width 0.1)
				(type default)
			)
			(layer "B.Fab")
		)
		(fp_line
			(start 0.2794 -0.1016)
			(end 0.2794 0.9906)
			(stroke
				(width 0.1)
				(type default)
			)
			(layer "B.Fab")
		)
		(pad "1" smd rect
			(at 0 0 90)
			(size 0.508 0.508)
			(layers "B.Cu" "B.Mask" "B.Paste")
			(net "PVDDQ_KLM")
		)
		(pad "2" smd rect
			(at 0 0.889 90)
			(size 0.508 0.508)
			(layers "B.Cu" "B.Mask" "B.Paste")
			(net "PWRGD_CPU1_DRAMPWROK_KLM_G")
		)
		(zone
			(layer "B.Cu")
			(hatch none 0.5)
			(connect_pads
				(clearance 0)
			)
			(min_thickness 0.25)
			(keepout
				(tracks not_allowed)
				(vias allowed)
				(pads allowed)
				(copperpour not_allowed)
				(footprints allowed)
			)
			(placement
				(enabled no)
				(sheetname "")
			)
			(fill
				(thermal_gap 0.5)
				(thermal_bridge_width 0.5)
				(island_removal_mode 0)
			)
			(polygon
				(pts
					(xy 155.779978 -119.130826) (xy 155.779978 -119.638826) (xy 156.160978 -119.638826) (xy 156.160978 -119.130826)
				)
			)
		)
		(zone
			(layer "B.Cu")
			(hatch none 0.5)
			(connect_pads
				(clearance 0)
			)
			(min_thickness 0.25)
			(keepout
				(tracks allowed)
				(vias not_allowed)
				(pads allowed)
				(copperpour not_allowed)
				(footprints allowed)
			)
			(placement
				(enabled no)
				(sheetname "")
			)
			(fill
				(thermal_gap 0.5)
				(thermal_bridge_width 0.5)
				(island_removal_mode 0)
			)
			(polygon
				(pts
					(xy 156.160978 -119.130826) (xy 156.160978 -119.638826) (xy 155.779978 -119.638826) (xy 155.779978 -119.130826)
				)
			)
		)
	)
	(footprint ""
		(layer "B.Cu")
		(at 276.000464 -17.7546 90)
		(property "Reference" "C5T5"
			(at -1.848866 0.752348 90)
			(unlocked yes)
			(layer "B.SilkS")
			(effects
				(font
					(size 1.27 0.9652)
					(thickness 0.1524)
				)
				(justify mirror)
			)
		)
		(property "Value" ""
			(at 0 0 90)
			(layer "B.Fab")
			(effects
				(font
					(size 1.27 1.27)
				)
				(justify mirror)
			)
		)
		(duplicate_pad_numbers_are_jumpers no)
		(fp_rect
			(start 0.500126 1.598422)
			(end -0.500126 -0.201422)
			(stroke
				(width 0)
				(type default)
			)
			(fill no)
			(layer "B.CrtYd")
		)
		(fp_line
			(start 0.500126 -0.201422)
			(end -0.500126 -0.201422)
			(stroke
				(width 0.1)
				(type default)
			)
			(layer "B.Fab")
		)
		(fp_line
			(start -0.500126 -0.201422)
			(end -0.500126 1.598422)
			(stroke
				(width 0.1)
				(type default)
			)
			(layer "B.Fab")
		)
		(fp_line
			(start 0.500126 1.598422)
			(end 0.500126 -0.201422)
			(stroke
				(width 0.1)
				(type default)
			)
			(layer "B.Fab")
		)
		(fp_line
			(start -0.500126 1.598422)
			(end 0.500126 1.598422)
			(stroke
				(width 0.1)
				(type default)
			)
			(layer "B.Fab")
		)
		(pad "1" smd rect
			(at 0 0)
			(size 0.889 0.9906)
			(layers "B.Cu" "B.Mask" "B.Paste")
			(net "PVDDQ_ABC")
		)
		(pad "2" smd rect
			(at 0 1.397)
			(size 0.889 0.9906)
			(layers "B.Cu" "B.Mask" "B.Paste")
			(net "GND")
		)
		(zone
			(layer "B.Cu")
			(hatch none 0.5)
			(connect_pads
				(clearance 0)
			)
			(min_thickness 0.25)
			(keepout
				(tracks not_allowed)
				(vias allowed)
				(pads allowed)
				(copperpour not_allowed)
				(footprints allowed)
			)
			(placement
				(enabled no)
				(sheetname "")
			)
			(fill
				(thermal_gap 0.5)
				(thermal_bridge_width 0.5)
				(island_removal_mode 0)
			)
			(polygon
				(pts
					(xy 276.952964 -18.2499) (xy 276.444964 -18.2499) (xy 276.444964 -17.2593) (xy 276.952964 -17.2593)
				)
			)
		)
		(zone
			(layer "B.Cu")
			(hatch none 0.5)
			(connect_pads
				(clearance 0)
			)
			(min_thickness 0.25)
			(keepout
				(tracks allowed)
				(vias not_allowed)
				(pads allowed)
				(copperpour not_allowed)
				(footprints allowed)
			)
			(placement
				(enabled no)
				(sheetname "")
			)
			(fill
				(thermal_gap 0.5)
				(thermal_bridge_width 0.5)
				(island_removal_mode 0)
			)
			(polygon
				(pts
					(xy 276.952964 -18.2499) (xy 276.444964 -18.2499) (xy 276.444964 -17.2593) (xy 276.952964 -17.2593)
				)
			)
		)
	)
	(footprint ""
		(layer "B.Cu")
		(at 484.850186 -121.325894 180)
		(property "Reference" "C9B10"
			(at 0.8382 -0.84963 180)
			(unlocked yes)
			(layer "B.SilkS")
			(effects
				(font
					(size 0.7874 0.5842)
					(thickness 0.1524)
				)
				(justify left mirror)
			)
		)
		(property "Value" ""
			(at 0 0 0)
			(layer "B.Fab")
			(effects
				(font
					(size 1.27 1.27)
				)
				(justify mirror)
			)
		)
		(duplicate_pad_numbers_are_jumpers no)
		(fp_poly
			(pts
				(xy -0.3048 -0.1016) (xy -0.3048 0.9906) (xy 0.3048 0.9906) (xy 0.3048 -0.1016)
			)
			(stroke
				(width 0)
				(type default)
			)
			(fill no)
			(layer "B.CrtYd")
		)
		(fp_line
			(start 0.3048 0.9906)
			(end -0.3048 0.9906)
			(stroke
				(width 0.1)
				(type default)
			)
			(layer "B.Fab")
		)
		(fp_line
			(start 0.3048 -0.1016)
			(end 0.3048 0.9906)
			(stroke
				(width 0.1)
				(type default)
			)
			(layer "B.Fab")
		)
		(fp_line
			(start -0.3048 0.9906)
			(end -0.3048 -0.1016)
			(stroke
				(width 0.1)
				(type default)
			)
			(layer "B.Fab")
		)
		(fp_line
			(start -0.3048 -0.1016)
			(end 0.3048 -0.1016)
			(stroke
				(width 0.1)
				(type default)
			)
			(layer "B.Fab")
		)
		(pad "1" smd rect
			(at 0 0)
			(size 0.508 0.508)
			(layers "B.Cu" "B.Mask" "B.Paste")
			(net "P5V_STBY")
		)
		(pad "2" smd rect
			(at 0 0.889)
			(size 0.508 0.508)
			(layers "B.Cu" "B.Mask" "B.Paste")
			(net "GND")
		)
		(zone
			(layer "B.Cu")
			(hatch none 0.5)
			(connect_pads
				(clearance 0)
			)
			(min_thickness 0.25)
			(keepout
				(tracks not_allowed)
				(vias allowed)
				(pads allowed)
				(copperpour not_allowed)
				(footprints allowed)
			)
			(placement
				(enabled no)
				(sheetname "")
			)
			(fill
				(thermal_gap 0.5)
				(thermal_bridge_width 0.5)
				(island_removal_mode 0)
			)
			(polygon
				(pts
					(xy 484.596186 -121.960894) (xy 485.104186 -121.960894) (xy 485.104186 -121.579894) (xy 484.596186 -121.579894)
				)
			)
		)
		(zone
			(layer "B.Cu")
			(hatch none 0.5)
			(connect_pads
				(clearance 0)
			)
			(min_thickness 0.25)
			(keepout
				(tracks allowed)
				(vias not_allowed)
				(pads allowed)
				(copperpour not_allowed)
				(footprints allowed)
			)
			(placement
				(enabled no)
				(sheetname "")
			)
			(fill
				(thermal_gap 0.5)
				(thermal_bridge_width 0.5)
				(island_removal_mode 0)
			)
			(polygon
				(pts
					(xy 484.596186 -121.579894) (xy 485.104186 -121.579894) (xy 485.104186 -121.960894) (xy 484.596186 -121.960894)
				)
			)
		)
	)
)
